# Bryce Canyon_Storage_Controller_Card_Stackup.xlsx — PCB Test Plan_HVM(0-90) (pcb-stackup)
|  | Board vendor give feedback of quantity in yellow columns based on the AQL table or description. |  |  |  |  |  |  |  |  |  |  |  |  |  |  |
|  | Wiwynn PM give feedback in blue columns |  |  |  |  |  |  |  |  |  |  |  |  |  |  |
| Person to be informed : PCB vendor, EE, SI, PM, PSM, Buyer, SQM |  |  |  |  |  |  |  |  |  |  |  |  |  |  |  |
| Simple flow : SI (test requirements) -> PM/AM (Total PCBS demand) -> Buyer -> Board Vendor (yellow column feedback) -> Buyer -> Person to be informed (Check and Track) |  |  |  |  |  |  |  |  |  |  |  |  |  |  |  |
| PO(purchase order) : If there are many POs for this PCB, 1st sample quantity is based on 1st PO, 2nd sample quantity is based on 2nd PO. |  |  |  |  |  |  |  |  |  |  |  |  |  |  |  |
| Project Name | PCB name | PCB# (1XXXX-XX) | Product Stage | Batch# | PCB Vendor | PCBs Demand | Delta-L Coupon (PCB Vendor) | Delta-L Coupon (3rd Party Lab) | Impedance Coupon (PCB Vendor) | In-board trace correlation (PCB Vendor) | X-section Analysis (PCB Vendor) | IST (3rd Party Lab) | Resin Void (PCB Vendor) | IPC-6012D (3rd Party Lab) | Note 1 |
| Bryce Canyon | SCC | 16316-1 | HVM(0-90 days) | N/A |  |  | Yes | Yes | Yes | Yes | No | Yes | No | No | Need Test? (Yes, No) |
| Tracking Code On Both Of Coupon And PCB |  |  |  |  |  |  | Follow rules of board vendor | Follow rules of board vendor | Follow rules of board vendor | Follow rules of board vendor |  | Follow rules of board vendor |  |  |  |
| Test Item Acceptance Criteria |  |  |  |  |  |  | Failure Rate ≦0.3% | Failure Rate ≦0.3% | Cpk≧1.0 | Fail : 0 Variation ≦5% |  | Fail: 0 |  |  |  |
| Test Item Sampling Quantity |  |  |  |  |  |  | AQL 1, level 1 | 30 pcs | AQL 1, level 1 | AQL 1, level 1 |  | 5 pcs/production lot, with max total of 30 pcs |  |  |  |
| Test Time (working days) |  |  |  |  |  |  | 5 | 5 | 5 | 5 |  | 20+ |  |  |  |
| Test Item Shipping Quantity |  |  |  |  |  |  |  | 30 pcs |  |  |  | 5 pcs/production lot, with max total of 30 pcs |  |  |  |
| Shipping Address |  |  |  |  |  |  |  | 8F, 90, Sec. 1, Xintai 5th Rd., Xizhi Dist., New Taipei City 22102, Taiwan, R.O.C. |  |  |  | 8F, 90, Sec. 1, Xintai 5th Rd., Xizhi Dist., New Taipei City 22102, Taiwan, R.O.C. |  |  |  |
| Receiver Name |  |  |  |  |  |  |  | Karol Lai |  |  |  | Karol Lai |  |  |  |
| Receiver Phone# |  |  |  |  |  |  |  | 886-2-6612-7507 |  |  |  | 886-2-6612-7507 |  |  |  |
